(kicad_pcb
	(version 20260206)
	(generator "pcbnew")
	(generator_version "10.0")
	(general
		(thickness 1.6)
		(legacy_teardrops no)
	)
	(paper "A4")
	(title_block
		(title "netronome-mezz — pcbd0082-001_rev01_jul9_a.brd")
		(comment 1 "Open CloudServer (Microsoft) / footprints 583-583 of 714")
	)
	(layers
		(0 "F.Cu" signal "TOP")
		(4 "In1.Cu" signal "02_GND")
		(6 "In2.Cu" signal "03_SIG")
		(8 "In3.Cu" signal "04_SIG")
		(10 "In4.Cu" signal "05_GND")
		(12 "In5.Cu" signal "06_PWR1")
		(14 "In6.Cu" signal "07_SIG")
		(16 "In7.Cu" signal "08_SIG")
		(18 "In8.Cu" signal "09_GND")
		(2 "B.Cu" signal "BOTTOM")
		(9 "F.Adhes" user "F.Adhesive")
		(11 "B.Adhes" user "B.Adhesive")
		(13 "F.Paste" user "Package Geometry/Pastemask Top")
		(15 "B.Paste" user "Package Geometry/Pastemask Bottom")
		(5 "F.SilkS" user "Ref Des/Silkscreen Top")
		(7 "B.SilkS" user "Ref Des/Silkscreen Bottom")
		(1 "F.Mask" user "Board Geometry/Soldermask Top")
		(3 "B.Mask" user "Board Geometry/Soldermask Bottom")
		(17 "Dwgs.User" user "User.Drawings")
		(19 "Cmts.User" user "User.Comments")
		(21 "Eco1.User" user "User.Eco1")
		(23 "Eco2.User" user "User.Eco2")
		(25 "Edge.Cuts" user "Board Geometry/Outline")
		(27 "Margin" user)
		(31 "F.CrtYd" user "Package Geometry/Place Bound Top")
		(29 "B.CrtYd" user "Package Geometry/Place Bound Bottom")
		(35 "F.Fab" user "Ref Des/Assembly Top")
		(33 "B.Fab" user "Ref Des/Assembly Bottom")
		(45 "User.4" user "COMPVAL_TYPE_BOTTOM")
	)
	(footprint ""
		(layer "B.Cu")
		(at 31.877 32.639)
		(property "Reference" "R174"
			(at -0.02667 4.953 270)
			(unlocked yes)
			(layer "B.SilkS")
			(effects
				(font
					(size 0.7874 0.5842)
					(thickness 0.127)
				)
				(justify left mirror)
			)
		)
		(property "Value" "0"
			(at 0.148158 1.3462 270)
			(unlocked yes)
			(layer "B.Fab")
			(hide yes)
			(effects
				(font
					(size 1.27 0.9652)
					(thickness 0.000001)
				)
				(justify left mirror)
			)
		)
		(property "Device Type" "REST1111"
			(at 0.148158 1.3462 270)
			(unlocked yes)
			(layer "B.Fab")
			(hide yes)
			(effects
				(font
					(size 1.27 0.9652)
					(thickness 0.000001)
				)
				(justify left mirror)
			)
		)
		(duplicate_pad_numbers_are_jumpers no)
		(fp_poly
			(pts
				(xy -0.635 1.0668) (xy -0.635 -1.0668) (xy 0.635 -1.0668) (xy 0.635 1.0668)
			)
			(stroke
				(width 0)
				(type default)
			)
			(fill no)
			(layer "B.CrtYd")
		)
		(fp_line
			(start -0.254 -0.508)
			(end -0.254 0.508)
			(stroke
				(width 0.0254)
				(type default)
			)
			(layer "B.Fab")
		)
		(fp_line
			(start -0.254 0.508)
			(end 0.254 0.508)
			(stroke
				(width 0.0254)
				(type default)
			)
			(layer "B.Fab")
		)
		(fp_line
			(start 0.254 -0.508)
			(end -0.254 -0.508)
			(stroke
				(width 0.0254)
				(type default)
			)
			(layer "B.Fab")
		)
		(fp_line
			(start 0.254 0.508)
			(end 0.254 -0.508)
			(stroke
				(width 0.0254)
				(type default)
			)
			(layer "B.Fab")
		)
		(pad "1" smd rect
			(at 0 -0.4191 180)
			(size 0.508 0.5334)
			(layers "B.Cu" "B.Mask" "B.Paste")
			(net "NFP_CORE_VID4")
		)
		(pad "2" smd rect
			(at 0 0.4191 180)
			(size 0.508 0.5334)
			(layers "B.Cu" "B.Mask" "B.Paste")
			(net "_NFP_CORE_VID4")
		)
		(zone
			(layer "B.Cu")
			(hatch none 0.5)
			(connect_pads
				(clearance 0)
			)
			(min_thickness 0.25)
			(keepout
				(tracks not_allowed)
				(vias allowed)
				(pads allowed)
				(copperpour not_allowed)
				(footprints allowed)
			)
			(placement
				(enabled no)
				(sheetname "")
			)
			(fill
				(thermal_gap 0.5)
				(thermal_bridge_width 0.5)
				(island_removal_mode 0)
			)
			(polygon
				(pts
					(xy 31.8516 32.6136) (xy 31.8516 32.6644) (xy 31.9024 32.6644) (xy 31.9024 32.6136)
				)
			)
		)
	)
)
